#ISCELL
  mstr_misc dns *
  *
#ISCELL
  pure_quanta quanta_title_block_c *
  *
#ISCELL
  pure_quanta_power universal_gnd *
  page469_i1
#ISCELL
  pure_quanta_power universal_gnd *
  page469_i10
#ISCELL
  pure_quanta_power universal_gnd *
  page469_i11
#CELL
  pure_quanta q_cap *
  page469_i12
#CELL
  pure_quanta q_res *
  page469_i13
#ISCELL
  mstr_symbols universal_power *
  page469_i14
#ISCELL
  pure_quanta_power universal_gnd *
  page469_i15
#CELL
  pure_quanta q_cap *
  page469_i16
#CELL
  pure_quanta q_cap *
  page469_i17
#CELL
  pure_quanta q_cap *
  page469_i18
#ISCELL
  pure_quanta_power universal_gnd *
  page469_i19
#ISCELL
  standard offpage *
  page469_i2
#CELL
  pure_quanta q_res *
  page469_i20
#CELL
  pure_quanta q_res *
  page469_i21
#CELL
  pure_quanta q_cap *
  page469_i22
#CELL
  pure_quanta q_cap *
  page469_i23
#ISCELL
  pure_quanta_power universal_gnd *
  page469_i24
#ISCELL
  pure_quanta_power universal_gnd *
  page469_i25
#CELL
  pure_quanta q_cap *
  page469_i26
#ISCELL
  pure_quanta_power universal_gnd *
  page469_i27
#CELL
  pure_quanta q_res *
  page469_i28
#CELL
  pure_quanta q_res *
  page469_i29
#ISCELL
  pure_quanta_power universal_gnd *
  page469_i3
#ISCELL
  mstr_symbols universal_power *
  page469_i30
#ISCELL
  pure_quanta_power universal_gnd *
  page469_i31
#CELL
  pure_quanta q_cap *
  page469_i32
#CELL
  pure_quanta q_res *
  page469_i33
#CELL
  pure_quanta q_cap *
  page469_i34
#CELL
  pure_quanta q_res *
  page469_i35
#CELL
  pure_quanta q_inductor *
  page469_i36
#CELL
  pure_quanta q_res *
  page469_i37
#CELL
  pure_quanta q_cap *
  page469_i38
#CELL
  pure_quanta q_cap *
  page469_i39
#CELL
  pure_quanta q_cap *
  page469_i4
#CELL
  pure_quanta q_cap *
  page469_i40
#ISCELL
  pure_quanta_power universal_gnd *
  page469_i41
#CELL
  pure_quanta q_cap *
  page469_i42
#ISCELL
  standard offpage *
  page469_i43
#CELL
  pure_quanta q_cap *
  page469_i44
#CELL
  pure_quanta q_capp *
  page469_i46
#ISCELL
  pure_quanta_power universal_gnd *
  page469_i47
#CELL
  pure_quanta q_capp *
  page469_i48
#CELL
  pure_quanta q_cap *
  page469_i49
#CELL
  pure_quanta q_cap *
  page469_i5
#ISCELL
  pure_quanta_power p1v0 *
  page469_i50
#CELL
  pure_quanta mpq8633bglec838z *
  page469_i51
#CELL
  pure_quanta q_cap *
  page469_i52
#CELL
  pure_quanta q_cap *
  page469_i56
#CELL
  pure_quanta q_cap *
  page469_i57
#CELL
  pure_quanta q_cap *
  page469_i58
#CELL
  pure_quanta q_capp *
  page469_i6
#CELL
  pure_quanta q_cap *
  page469_i7
#ISCELL
  mstr_symbols p1v0_aux *
  page469_i8
#CELL
  pure_quanta q_inductor *
  page469_i9
